(kicad_pcb
	(version 20260206)
	(generator "pcbnew")
	(generator_version "10.0")
	(general
		(thickness 1.6)
		(legacy_teardrops no)
	)
	(paper "A4")
	(title_block
		(title "peb — Lightning_PEB_BRD.brd")
		(comment 1 "Lightning (Wiwynn / Facebook NVMe JBOF) / footprints 2499-2505 of 2563")
	)
	(layers
		(0 "F.Cu" signal "TOP")
		(4 "In1.Cu" signal "L2GND")
		(6 "In2.Cu" signal "L3")
		(8 "In3.Cu" signal "L4VCC")
		(10 "In4.Cu" signal "L5VCC")
		(12 "In5.Cu" signal "L6")
		(14 "In6.Cu" signal "L7GND")
		(2 "B.Cu" signal "BOTTOM")
		(9 "F.Adhes" user "F.Adhesive")
		(11 "B.Adhes" user "B.Adhesive")
		(13 "F.Paste" user "Package Geometry/Pastemask Top")
		(15 "B.Paste" user "Package Geometry/Pastemask Bottom")
		(5 "F.SilkS" user "Ref Des/Silkscreen Top")
		(7 "B.SilkS" user "Ref Des/Silkscreen Bottom")
		(1 "F.Mask" user "Board Geometry/Soldermask Top")
		(3 "B.Mask" user "Board Geometry/Soldermask Bottom")
		(17 "Dwgs.User" user "User.Drawings")
		(19 "Cmts.User" user "User.Comments")
		(21 "Eco1.User" user "User.Eco1")
		(23 "Eco2.User" user "User.Eco2")
		(25 "Edge.Cuts" user "Board Geometry/Outline")
		(27 "Margin" user)
		(31 "F.CrtYd" user "Package Geometry/Place Bound Top")
		(29 "B.CrtYd" user "Package Geometry/Place Bound Bottom")
		(35 "F.Fab" user "Ref Des/Assembly Top")
		(33 "B.Fab" user "Ref Des/Assembly Bottom")
	)
	(footprint ""
		(layer "B.Cu")
		(at 252.603 -54.995572 -90)
		(property "Reference" "C580"
			(at 0 0 90)
			(layer "B.SilkS")
			(hide yes)
			(effects
				(font
					(size 1.27 1.27)
				)
				(justify mirror)
			)
		)
		(property "Value" "SCD1U16V1KX-1-GP"
			(at 2.8321 -1.7399 270)
			(unlocked yes)
			(layer "B.Fab")
			(hide yes)
			(effects
				(font
					(size 1.016 1.016)
					(thickness 0.1524)
				)
				(justify mirror)
			)
		)
		(property "Device Type" "C0201H13"
			(at 2.8321 -3.2639 270)
			(unlocked yes)
			(layer "B.Fab")
			(hide yes)
			(effects
				(font
					(size 1.016 1.016)
					(thickness 0.1524)
				)
				(justify mirror)
			)
		)
		(duplicate_pad_numbers_are_jumpers no)
		(fp_rect
			(start 0.2794 0.6477)
			(end -0.2794 -0.6477)
			(stroke
				(width 0)
				(type default)
			)
			(fill no)
			(layer "B.CrtYd")
		)
		(fp_rect
			(start 0.2794 0.6477)
			(end -0.2794 -0.6477)
			(stroke
				(width 0)
				(type default)
			)
			(fill no)
			(layer "B.Fab")
		)
		(pad "1" smd custom
			(at 0 -0.2794 90)
			(size 0.0762 0.0762)
			(layers "B.Cu" "B.Mask" "B.Paste")
			(net "DUT_AVD_PCIE")
			(options
				(clearance outline)
				(anchor circle)
			)
			(primitives
				(gr_poly
					(pts
						(arc
							(start 0.1524 0.127)
							(mid 0.137521 0.162921)
							(end 0.1016 0.1778)
						)
						(arc
							(start -0.1016 0.1778)
							(mid -0.137521 0.162921)
							(end -0.1524 0.127)
						)
						(arc
							(start -0.1524 -0.127)
							(mid -0.137521 -0.162921)
							(end -0.1016 -0.1778)
						)
						(arc
							(start 0.1016 -0.1778)
							(mid 0.137521 -0.162921)
							(end 0.1524 -0.127)
						)
					)
					(width 0)
					(fill yes)
				)
			)
		)
		(pad "2" smd custom
			(at 0 0.2794 90)
			(size 0.0762 0.0762)
			(layers "B.Cu" "B.Mask" "B.Paste")
			(net "GND")
			(options
				(clearance outline)
				(anchor circle)
			)
			(primitives
				(gr_poly
					(pts
						(arc
							(start 0.1524 0.127)
							(mid 0.137521 0.162921)
							(end 0.1016 0.1778)
						)
						(arc
							(start -0.1016 0.1778)
							(mid -0.137521 0.162921)
							(end -0.1524 0.127)
						)
						(arc
							(start -0.1524 -0.127)
							(mid -0.137521 -0.162921)
							(end -0.1016 -0.1778)
						)
						(arc
							(start 0.1016 -0.1778)
							(mid 0.137521 -0.162921)
							(end 0.1524 -0.127)
						)
					)
					(width 0)
					(fill yes)
				)
			)
		)
	)
	(footprint ""
		(layer "B.Cu")
		(at 248.60504 -60.071)
		(property "Reference" "C601"
			(at 0 0 0)
			(layer "B.SilkS")
			(hide yes)
			(effects
				(font
					(size 1.27 1.27)
				)
				(justify mirror)
			)
		)
		(property "Value" "SCD1U16V1KX-1-GP"
			(at 2.8321 -1.7399 0)
			(unlocked yes)
			(layer "B.Fab")
			(hide yes)
			(effects
				(font
					(size 1.016 1.016)
					(thickness 0.1524)
				)
				(justify mirror)
			)
		)
		(property "Device Type" "C0201H13"
			(at 2.8321 -3.2639 0)
			(unlocked yes)
			(layer "B.Fab")
			(hide yes)
			(effects
				(font
					(size 1.016 1.016)
					(thickness 0.1524)
				)
				(justify mirror)
			)
		)
		(duplicate_pad_numbers_are_jumpers no)
		(fp_rect
			(start 0.2794 0.6477)
			(end -0.2794 -0.6477)
			(stroke
				(width 0)
				(type default)
			)
			(fill no)
			(layer "B.CrtYd")
		)
		(fp_rect
			(start 0.2794 0.6477)
			(end -0.2794 -0.6477)
			(stroke
				(width 0)
				(type default)
			)
			(fill no)
			(layer "B.Fab")
		)
		(pad "1" smd custom
			(at 0 -0.2794 180)
			(size 0.0762 0.0762)
			(layers "B.Cu" "B.Mask" "B.Paste")
			(net "DUT_AVD_PCIE")
			(options
				(clearance outline)
				(anchor circle)
			)
			(primitives
				(gr_poly
					(pts
						(arc
							(start 0.1524 0.127)
							(mid 0.137521 0.162921)
							(end 0.1016 0.1778)
						)
						(arc
							(start -0.1016 0.1778)
							(mid -0.137521 0.162921)
							(end -0.1524 0.127)
						)
						(arc
							(start -0.1524 -0.127)
							(mid -0.137521 -0.162921)
							(end -0.1016 -0.1778)
						)
						(arc
							(start 0.1016 -0.1778)
							(mid 0.137521 -0.162921)
							(end 0.1524 -0.127)
						)
					)
					(width 0)
					(fill yes)
				)
			)
		)
		(pad "2" smd custom
			(at 0 0.2794 180)
			(size 0.0762 0.0762)
			(layers "B.Cu" "B.Mask" "B.Paste")
			(net "GND")
			(options
				(clearance outline)
				(anchor circle)
			)
			(primitives
				(gr_poly
					(pts
						(arc
							(start 0.1524 0.127)
							(mid 0.137521 0.162921)
							(end 0.1016 0.1778)
						)
						(arc
							(start -0.1016 0.1778)
							(mid -0.137521 0.162921)
							(end -0.1524 0.127)
						)
						(arc
							(start -0.1524 -0.127)
							(mid -0.137521 -0.162921)
							(end -0.1016 -0.1778)
						)
						(arc
							(start 0.1016 -0.1778)
							(mid 0.137521 -0.162921)
							(end 0.1524 -0.127)
						)
					)
					(width 0)
					(fill yes)
				)
			)
		)
	)
	(footprint ""
		(layer "B.Cu")
		(at 54.010052 -112.22863 90)
		(property "Reference" "R40"
			(at 0 0 90)
			(layer "B.SilkS")
			(hide yes)
			(effects
				(font
					(size 1.27 1.27)
				)
				(justify mirror)
			)
		)
		(property "Value" "0R2J-2-GP"
			(at -0.064008 -3.993896 90)
			(unlocked yes)
			(layer "B.Fab")
			(hide yes)
			(effects
				(font
					(size 1.016 1.016)
					(thickness 0.1524)
				)
				(justify mirror)
			)
		)
		(property "Device Type" "R402H16"
			(at -0.064008 -5.517896 90)
			(unlocked yes)
			(layer "B.Fab")
			(hide yes)
			(effects
				(font
					(size 1.016 1.016)
					(thickness 0.1524)
				)
				(justify mirror)
			)
		)
		(duplicate_pad_numbers_are_jumpers no)
		(fp_line
			(start 0.508 -0.9398)
			(end 0.508 0.9398)
			(stroke
				(width 0.1524)
				(type default)
			)
			(layer "B.SilkS")
		)
		(fp_line
			(start -0.508 -0.9398)
			(end 0.508 -0.9398)
			(stroke
				(width 0.1524)
				(type default)
			)
			(layer "B.SilkS")
		)
		(fp_rect
			(start 0.508 0.9398)
			(end -0.508 -0.9398)
			(stroke
				(width 0)
				(type default)
			)
			(fill no)
			(layer "B.CrtYd")
		)
		(fp_rect
			(start 0.508 0.9398)
			(end -0.508 -0.9398)
			(stroke
				(width 0)
				(type default)
			)
			(fill no)
			(layer "B.Fab")
		)
		(pad "1" smd custom
			(at 0 -0.4445 270)
			(size 0.1397 0.1397)
			(layers "B.Cu" "B.Mask" "B.Paste")
			(net "BMC_I2C12_MINI6_SDA")
			(options
				(clearance outline)
				(anchor circle)
			)
			(primitives
				(gr_poly
					(pts
						(arc
							(start -0.1778 0.2794)
							(mid -0.249642 0.249642)
							(end -0.2794 0.1778)
						)
						(arc
							(start -0.2794 -0.1778)
							(mid -0.249642 -0.249642)
							(end -0.1778 -0.2794)
						)
						(arc
							(start 0.1778 -0.2794)
							(mid 0.249642 -0.249642)
							(end 0.2794 -0.1778)
						)
						(arc
							(start 0.2794 0.1778)
							(mid 0.249642 0.249642)
							(end 0.1778 0.2794)
						)
					)
					(width 0)
					(fill yes)
				)
			)
		)
		(pad "2" smd custom
			(at 0 0.4445 270)
			(size 0.1397 0.1397)
			(layers "B.Cu" "B.Mask" "B.Paste")
			(net "BMC_I2C12_MINI6_SDA_S")
			(options
				(clearance outline)
				(anchor circle)
			)
			(primitives
				(gr_poly
					(pts
						(arc
							(start -0.1778 0.2794)
							(mid -0.249642 0.249642)
							(end -0.2794 0.1778)
						)
						(arc
							(start -0.2794 -0.1778)
							(mid -0.249642 -0.249642)
							(end -0.1778 -0.2794)
						)
						(arc
							(start 0.1778 -0.2794)
							(mid 0.249642 -0.249642)
							(end 0.2794 -0.1778)
						)
						(arc
							(start 0.2794 0.1778)
							(mid 0.249642 0.249642)
							(end 0.1778 0.2794)
						)
					)
					(width 0)
					(fill yes)
				)
			)
		)
	)
	(footprint ""
		(layer "B.Cu")
		(at 227.6856 -41.004744 -90)
		(property "Reference" "C557"
			(at 0 0 90)
			(layer "B.SilkS")
			(hide yes)
			(effects
				(font
					(size 1.27 1.27)
				)
				(justify mirror)
			)
		)
		(property "Value" "SCD1U16V1KX-1-GP"
			(at 2.8321 -1.7399 270)
			(unlocked yes)
			(layer "B.Fab")
			(hide yes)
			(effects
				(font
					(size 1.016 1.016)
					(thickness 0.1524)
				)
				(justify mirror)
			)
		)
		(property "Device Type" "C0201H13"
			(at 2.8321 -3.2639 270)
			(unlocked yes)
			(layer "B.Fab")
			(hide yes)
			(effects
				(font
					(size 1.016 1.016)
					(thickness 0.1524)
				)
				(justify mirror)
			)
		)
		(duplicate_pad_numbers_are_jumpers no)
		(fp_rect
			(start 0.2794 0.6477)
			(end -0.2794 -0.6477)
			(stroke
				(width 0)
				(type default)
			)
			(fill no)
			(layer "B.CrtYd")
		)
		(fp_rect
			(start 0.2794 0.6477)
			(end -0.2794 -0.6477)
			(stroke
				(width 0)
				(type default)
			)
			(fill no)
			(layer "B.Fab")
		)
		(pad "1" smd custom
			(at 0 -0.2794 90)
			(size 0.0762 0.0762)
			(layers "B.Cu" "B.Mask" "B.Paste")
			(net "DUT_AVD_PCIE")
			(options
				(clearance outline)
				(anchor circle)
			)
			(primitives
				(gr_poly
					(pts
						(arc
							(start 0.1524 0.127)
							(mid 0.137521 0.162921)
							(end 0.1016 0.1778)
						)
						(arc
							(start -0.1016 0.1778)
							(mid -0.137521 0.162921)
							(end -0.1524 0.127)
						)
						(arc
							(start -0.1524 -0.127)
							(mid -0.137521 -0.162921)
							(end -0.1016 -0.1778)
						)
						(arc
							(start 0.1016 -0.1778)
							(mid 0.137521 -0.162921)
							(end 0.1524 -0.127)
						)
					)
					(width 0)
					(fill yes)
				)
			)
		)
		(pad "2" smd custom
			(at 0 0.2794 90)
			(size 0.0762 0.0762)
			(layers "B.Cu" "B.Mask" "B.Paste")
			(net "GND")
			(options
				(clearance outline)
				(anchor circle)
			)
			(primitives
				(gr_poly
					(pts
						(arc
							(start 0.1524 0.127)
							(mid 0.137521 0.162921)
							(end 0.1016 0.1778)
						)
						(arc
							(start -0.1016 0.1778)
							(mid -0.137521 0.162921)
							(end -0.1524 0.127)
						)
						(arc
							(start -0.1524 -0.127)
							(mid -0.137521 -0.162921)
							(end -0.1016 -0.1778)
						)
						(arc
							(start 0.1016 -0.1778)
							(mid 0.137521 -0.162921)
							(end 0.1524 -0.127)
						)
					)
					(width 0)
					(fill yes)
				)
			)
		)
	)
	(footprint ""
		(layer "B.Cu")
		(at 50.2412 -113.157)
		(property "Reference" "R411"
			(at 0 0 0)
			(layer "B.SilkS")
			(hide yes)
			(effects
				(font
					(size 1.27 1.27)
				)
				(justify mirror)
			)
		)
		(property "Value" "4K7R2F-GP"
			(at -0.064008 -3.993896 0)
			(unlocked yes)
			(layer "B.Fab")
			(hide yes)
			(effects
				(font
					(size 1.016 1.016)
					(thickness 0.1524)
				)
				(justify mirror)
			)
		)
		(property "Device Type" "R402H16"
			(at -0.064008 -5.517896 0)
			(unlocked yes)
			(layer "B.Fab")
			(hide yes)
			(effects
				(font
					(size 1.016 1.016)
					(thickness 0.1524)
				)
				(justify mirror)
			)
		)
		(duplicate_pad_numbers_are_jumpers no)
		(fp_line
			(start -0.508 -0.9398)
			(end 0.508 -0.9398)
			(stroke
				(width 0.1524)
				(type default)
			)
			(layer "B.SilkS")
		)
		(fp_line
			(start 0.508 -0.9398)
			(end 0.508 0.9398)
			(stroke
				(width 0.1524)
				(type default)
			)
			(layer "B.SilkS")
		)
		(fp_rect
			(start 0.508 0.9398)
			(end -0.508 -0.9398)
			(stroke
				(width 0)
				(type default)
			)
			(fill no)
			(layer "B.CrtYd")
		)
		(fp_rect
			(start 0.508 0.9398)
			(end -0.508 -0.9398)
			(stroke
				(width 0)
				(type default)
			)
			(fill no)
			(layer "B.Fab")
		)
		(pad "1" smd custom
			(at 0 -0.4445 180)
			(size 0.1397 0.1397)
			(layers "B.Cu" "B.Mask" "B.Paste")
			(net "BMC_I2C10_8536_SCL")
			(options
				(clearance outline)
				(anchor circle)
			)
			(primitives
				(gr_poly
					(pts
						(arc
							(start -0.1778 0.2794)
							(mid -0.249642 0.249642)
							(end -0.2794 0.1778)
						)
						(arc
							(start -0.2794 -0.1778)
							(mid -0.249642 -0.249642)
							(end -0.1778 -0.2794)
						)
						(arc
							(start 0.1778 -0.2794)
							(mid 0.249642 -0.249642)
							(end 0.2794 -0.1778)
						)
						(arc
							(start 0.2794 0.1778)
							(mid 0.249642 0.249642)
							(end 0.1778 0.2794)
						)
					)
					(width 0)
					(fill yes)
				)
			)
		)
		(pad "2" smd custom
			(at 0 0.4445 180)
			(size 0.1397 0.1397)
			(layers "B.Cu" "B.Mask" "B.Paste")
			(net "P3V3_STBY")
			(options
				(clearance outline)
				(anchor circle)
			)
			(primitives
				(gr_poly
					(pts
						(arc
							(start -0.1778 0.2794)
							(mid -0.249642 0.249642)
							(end -0.2794 0.1778)
						)
						(arc
							(start -0.2794 -0.1778)
							(mid -0.249642 -0.249642)
							(end -0.1778 -0.2794)
						)
						(arc
							(start 0.1778 -0.2794)
							(mid 0.249642 -0.249642)
							(end 0.2794 -0.1778)
						)
						(arc
							(start 0.2794 0.1778)
							(mid 0.249642 0.249642)
							(end 0.1778 0.2794)
						)
					)
					(width 0)
					(fill yes)
				)
			)
		)
	)
	(footprint ""
		(layer "B.Cu")
		(at 124.9426 -199.7456)
		(property "Reference" "R3224"
			(at 0 0 0)
			(layer "B.SilkS")
			(hide yes)
			(effects
				(font
					(size 1.27 1.27)
				)
				(justify mirror)
			)
		)
		(property "Value" "0R2J-2-GP"
			(at -0.064008 -3.993896 0)
			(unlocked yes)
			(layer "B.Fab")
			(hide yes)
			(effects
				(font
					(size 1.016 1.016)
					(thickness 0.1524)
				)
				(justify mirror)
			)
		)
		(property "Device Type" "R402H16"
			(at -0.064008 -5.517896 0)
			(unlocked yes)
			(layer "B.Fab")
			(hide yes)
			(effects
				(font
					(size 1.016 1.016)
					(thickness 0.1524)
				)
				(justify mirror)
			)
		)
		(duplicate_pad_numbers_are_jumpers no)
		(fp_line
			(start -0.508 -0.9398)
			(end 0.508 -0.9398)
			(stroke
				(width 0.1524)
				(type default)
			)
			(layer "B.SilkS")
		)
		(fp_line
			(start 0.508 -0.9398)
			(end 0.508 0.9398)
			(stroke
				(width 0.1524)
				(type default)
			)
			(layer "B.SilkS")
		)
		(fp_rect
			(start 0.508 0.9398)
			(end -0.508 -0.9398)
			(stroke
				(width 0)
				(type default)
			)
			(fill no)
			(layer "B.CrtYd")
		)
		(fp_rect
			(start 0.508 0.9398)
			(end -0.508 -0.9398)
			(stroke
				(width 0)
				(type default)
			)
			(fill no)
			(layer "B.Fab")
		)
		(pad "1" smd custom
			(at 0 -0.4445 180)
			(size 0.1397 0.1397)
			(layers "B.Cu" "B.Mask" "B.Paste")
			(net "SSD_PERST_Y7")
			(options
				(clearance outline)
				(anchor circle)
			)
			(primitives
				(gr_poly
					(pts
						(arc
							(start -0.1778 0.2794)
							(mid -0.249642 0.249642)
							(end -0.2794 0.1778)
						)
						(arc
							(start -0.2794 -0.1778)
							(mid -0.249642 -0.249642)
							(end -0.1778 -0.2794)
						)
						(arc
							(start 0.1778 -0.2794)
							(mid 0.249642 -0.249642)
							(end 0.2794 -0.1778)
						)
						(arc
							(start 0.2794 0.1778)
							(mid 0.249642 0.249642)
							(end 0.1778 0.2794)
						)
					)
					(width 0)
					(fill yes)
				)
			)
		)
		(pad "2" smd custom
			(at 0 0.4445 180)
			(size 0.1397 0.1397)
			(layers "B.Cu" "B.Mask" "B.Paste")
			(net "SSD_PERST#7_R")
			(options
				(clearance outline)
				(anchor circle)
			)
			(primitives
				(gr_poly
					(pts
						(arc
							(start -0.1778 0.2794)
							(mid -0.249642 0.249642)
							(end -0.2794 0.1778)
						)
						(arc
							(start -0.2794 -0.1778)
							(mid -0.249642 -0.249642)
							(end -0.1778 -0.2794)
						)
						(arc
							(start 0.1778 -0.2794)
							(mid 0.249642 -0.249642)
							(end 0.2794 -0.1778)
						)
						(arc
							(start 0.2794 0.1778)
							(mid 0.249642 0.249642)
							(end 0.1778 0.2794)
						)
					)
					(width 0)
					(fill yes)
				)
			)
		)
	)
	(footprint ""
		(layer "B.Cu")
		(at 20.914868 -117.741446 -90)
		(property "Reference" "R711"
			(at 0 0 90)
			(layer "B.SilkS")
			(hide yes)
			(effects
				(font
					(size 1.27 1.27)
				)
				(justify mirror)
			)
		)
		(property "Value" "0R2J-2-GP"
			(at -0.064008 -3.993896 270)
			(unlocked yes)
			(layer "B.Fab")
			(hide yes)
			(effects
				(font
					(size 1.016 1.016)
					(thickness 0.1524)
				)
				(justify mirror)
			)
		)
		(property "Device Type" "R402H16"
			(at -0.064008 -5.517896 270)
			(unlocked yes)
			(layer "B.Fab")
			(hide yes)
			(effects
				(font
					(size 1.016 1.016)
					(thickness 0.1524)
				)
				(justify mirror)
			)
		)
		(duplicate_pad_numbers_are_jumpers no)
		(fp_line
			(start -0.508 -0.9398)
			(end 0.508 -0.9398)
			(stroke
				(width 0.1524)
				(type default)
			)
			(layer "B.SilkS")
		)
		(fp_line
			(start 0.508 -0.9398)
			(end 0.508 0.9398)
			(stroke
				(width 0.1524)
				(type default)
			)
			(layer "B.SilkS")
		)
		(fp_rect
			(start 0.508 0.9398)
			(end -0.508 -0.9398)
			(stroke
				(width 0)
				(type default)
			)
			(fill no)
			(layer "B.CrtYd")
		)
		(fp_rect
			(start 0.508 0.9398)
			(end -0.508 -0.9398)
			(stroke
				(width 0)
				(type default)
			)
			(fill no)
			(layer "B.Fab")
		)
		(pad "1" smd custom
			(at 0 -0.4445 90)
			(size 0.1397 0.1397)
			(layers "B.Cu" "B.Mask" "B.Paste")
			(net "SPIDI_R")
			(options
				(clearance outline)
				(anchor circle)
			)
			(primitives
				(gr_poly
					(pts
						(arc
							(start -0.1778 0.2794)
							(mid -0.249642 0.249642)
							(end -0.2794 0.1778)
						)
						(arc
							(start -0.2794 -0.1778)
							(mid -0.249642 -0.249642)
							(end -0.1778 -0.2794)
						)
						(arc
							(start 0.1778 -0.2794)
							(mid 0.249642 -0.249642)
							(end 0.2794 -0.1778)
						)
						(arc
							(start 0.2794 0.1778)
							(mid 0.249642 0.249642)
							(end 0.1778 0.2794)
						)
					)
					(width 0)
					(fill yes)
				)
			)
		)
		(pad "2" smd custom
			(at 0 0.4445 90)
			(size 0.1397 0.1397)
			(layers "B.Cu" "B.Mask" "B.Paste")
			(net "SPIDI")
			(options
				(clearance outline)
				(anchor circle)
			)
			(primitives
				(gr_poly
					(pts
						(arc
							(start -0.1778 0.2794)
							(mid -0.249642 0.249642)
							(end -0.2794 0.1778)
						)
						(arc
							(start -0.2794 -0.1778)
							(mid -0.249642 -0.249642)
							(end -0.1778 -0.2794)
						)
						(arc
							(start 0.1778 -0.2794)
							(mid 0.249642 -0.249642)
							(end 0.2794 -0.1778)
						)
						(arc
							(start 0.2794 0.1778)
							(mid 0.249642 0.249642)
							(end 0.1778 0.2794)
						)
					)
					(width 0)
					(fill yes)
				)
			)
		)
	)
)
